# T6G (Grand Teton) — schematic netlist excerpt (pin names and nets, part order shuffled) for the footprints in the layout excerpt that follows; sources: Cadence DE-HDL packaged netlist, KiCad conversion of 04192023_DAF0TMB3IC0_F0TG_MB_C_brd_V02_OCP.brd

PC386  Q_CAP  0.22UF 16V 10% X7R  pkg 0402  page 218 : A = SW_PVDDCR_CPU1_P1_BOOT2_R ; B = SW_PVDDCR_CPU1_P1_BOOTR2
R3770  Q_RES  0 5% CHIP  pkg 0402LF  page 241 : A = GPU_PRSNT ; B = GPU_PRSNT_R
R1019  Q_RES  10K 1% CHIP  pkg 0201LF  page 287 : A = RST_RT_CPU0_P1_PERST_R_N ; B = GND

(kicad_pcb
	(version 20260206)
	(generator "pcbnew")
	(generator_version "10.0")
	(general
		(thickness 1.6)
		(legacy_teardrops no)
	)
	(paper "A4")
	(title_block
		(title "04192023_DAF0TMB3IC0_F0TG_MB_C_brd_V02_OCP.brd")
		(comment 1 "Grand Teton / footprints 3827-3830 of 8354")
	)
	(layers
		(0 "F.Cu" signal "TOP")
		(4 "In1.Cu" signal "GND")
		(6 "In2.Cu" signal "IN1")
		(8 "In3.Cu" signal "GND1")
		(10 "In4.Cu" signal "IN2")
		(12 "In5.Cu" signal "GND2")
		(14 "In6.Cu" signal "IN3")
		(16 "In7.Cu" signal "GND3")
		(18 "In8.Cu" signal "VCC")
		(20 "In9.Cu" signal "VCC1")
		(22 "In10.Cu" signal "GND4")
		(24 "In11.Cu" signal "IN4")
		(26 "In12.Cu" signal "GND5")
		(28 "In13.Cu" signal "IN5")
		(30 "In14.Cu" signal "GND6")
		(32 "In15.Cu" signal "IN6")
		(34 "In16.Cu" signal "GND7")
		(2 "B.Cu" signal "BOTTOM")
		(9 "F.Adhes" user "F.Adhesive")
		(11 "B.Adhes" user "B.Adhesive")
		(13 "F.Paste" user "Package Geometry/Pastemask Top")
		(15 "B.Paste" user "Package Geometry/Pastemask Bottom")
		(5 "F.SilkS" user "Ref Des/Silkscreen Top")
		(7 "B.SilkS" user "Ref Des/Silkscreen Bottom")
		(1 "F.Mask" user "Board Geometry/Soldermask Top")
		(3 "B.Mask" user "Board Geometry/Soldermask Bottom")
		(17 "Dwgs.User" user "User.Drawings")
		(19 "Cmts.User" user "User.Comments")
		(21 "Eco1.User" user "User.Eco1")
		(23 "Eco2.User" user "User.Eco2")
		(25 "Edge.Cuts" user "Board Geometry/Outline")
		(27 "Margin" user)
		(31 "F.CrtYd" user "Package Geometry/Place Bound Top")
		(29 "B.CrtYd" user "Package Geometry/Place Bound Bottom")
		(35 "F.Fab" user "Ref Des/Assembly Top")
		(33 "B.Fab" user "Ref Des/Assembly Bottom")
	)
	(footprint ""
		(layer "F.Cu")
		(at 356.69601 -402.7424 -90)
		(property "Reference" "R1019"
			(at 0 0 270)
			(layer "F.SilkS")
			(hide yes)
			(effects
				(font
					(size 1.27 1.27)
				)
			)
		)
		(property "Value" ""
			(at 0 0 270)
			(layer "F.Fab")
			(effects
				(font
					(size 1.27 1.27)
				)
			)
		)
		(duplicate_pad_numbers_are_jumpers no)
		(fp_line
			(start -0.32512 0.175006)
			(end -0.32512 -0.175006)
			(stroke
				(width 0.1)
				(type default)
			)
			(layer "F.Fab")
		)
		(fp_line
			(start 0.32512 0.175006)
			(end -0.32512 0.175006)
			(stroke
				(width 0.1)
				(type default)
			)
			(layer "F.Fab")
		)
		(fp_line
			(start -0.32512 -0.175006)
			(end 0.32512 -0.175006)
			(stroke
				(width 0.1)
				(type default)
			)
			(layer "F.Fab")
		)
		(fp_line
			(start 0.32512 -0.175006)
			(end 0.32512 0.175006)
			(stroke
				(width 0.1)
				(type default)
			)
			(layer "F.Fab")
		)
		(pad "1" smd rect
			(at -0.2667 0 270)
			(size 0.3048 0.381)
			(layers "F.Cu" "F.Mask" "F.Paste")
			(net "RST_RT_CPU0_P1_PERST_R_N")
		)
		(pad "2" smd rect
			(at 0.2667 0 90)
			(size 0.3048 0.381)
			(layers "F.Cu" "F.Mask" "F.Paste")
			(net "GND")
		)
	)
	(footprint ""
		(layer "F.Cu")
		(at 58.017918 -83.554062)
		(property "Reference" "ME1"
			(at 0.1016 -5.9055 0)
			(unlocked yes)
			(layer "F.SilkS")
			(effects
				(font
					(size 0.254 0.127)
					(thickness 0.000001)
				)
				(justify left)
			)
		)
		(property "Value" ""
			(at 0 0 0)
			(layer "F.Fab")
			(effects
				(font
					(size 1.27 1.27)
				)
			)
		)
		(duplicate_pad_numbers_are_jumpers no)
	)
	(footprint ""
		(layer "F.Cu")
		(at 193.48958 -413.964882 90)
		(property "Reference" "R3770"
			(at 0 0 90)
			(layer "F.SilkS")
			(hide yes)
			(effects
				(font
					(size 1.27 1.27)
				)
			)
		)
		(property "Value" ""
			(at 0 0 90)
			(layer "F.Fab")
			(effects
				(font
					(size 1.27 1.27)
				)
			)
		)
		(duplicate_pad_numbers_are_jumpers no)
		(fp_line
			(start 0.7874 -0.4064)
			(end 0.7874 0.4064)
			(stroke
				(width 0.1524)
				(type default)
			)
			(layer "F.SilkS")
		)
		(fp_line
			(start -0.7874 -0.4064)
			(end 0.7874 -0.4064)
			(stroke
				(width 0.1524)
				(type default)
			)
			(layer "F.SilkS")
		)
		(fp_line
			(start 0.7874 0.4064)
			(end -0.7874 0.4064)
			(stroke
				(width 0.1524)
				(type default)
			)
			(layer "F.SilkS")
		)
		(fp_line
			(start -0.7874 0.4064)
			(end -0.7874 -0.4064)
			(stroke
				(width 0.1524)
				(type default)
			)
			(layer "F.SilkS")
		)
		(fp_line
			(start -0.12065 -0.305054)
			(end -0.12065 -0.2794)
			(stroke
				(width 0.1)
				(type default)
			)
			(layer "F.Fab")
		)
		(fp_line
			(start -0.67945 -0.305054)
			(end -0.12065 -0.305054)
			(stroke
				(width 0.1)
				(type default)
			)
			(layer "F.Fab")
		)
		(fp_line
			(start 0.67945 -0.3048)
			(end 0.67945 0.3048)
			(stroke
				(width 0.1)
				(type default)
			)
			(layer "F.Fab")
		)
		(fp_line
			(start 0.12065 -0.3048)
			(end 0.67945 -0.3048)
			(stroke
				(width 0.1)
				(type default)
			)
			(layer "F.Fab")
		)
		(fp_line
			(start 0.12065 -0.2794)
			(end 0.12065 -0.3048)
			(stroke
				(width 0.1)
				(type default)
			)
			(layer "F.Fab")
		)
		(fp_line
			(start -0.12065 -0.2794)
			(end 0.12065 -0.2794)
			(stroke
				(width 0.1)
				(type default)
			)
			(layer "F.Fab")
		)
		(fp_line
			(start 0.120396 0.2794)
			(end -0.12065 0.2794)
			(stroke
				(width 0.1)
				(type default)
			)
			(layer "F.Fab")
		)
		(fp_line
			(start -0.12065 0.2794)
			(end -0.12065 0.3048)
			(stroke
				(width 0.1)
				(type default)
			)
			(layer "F.Fab")
		)
		(fp_line
			(start 0.67945 0.3048)
			(end 0.120396 0.3048)
			(stroke
				(width 0.1)
				(type default)
			)
			(layer "F.Fab")
		)
		(fp_line
			(start 0.120396 0.3048)
			(end 0.120396 0.2794)
			(stroke
				(width 0.1)
				(type default)
			)
			(layer "F.Fab")
		)
		(fp_line
			(start -0.12065 0.3048)
			(end -0.67945 0.3048)
			(stroke
				(width 0.1)
				(type default)
			)
			(layer "F.Fab")
		)
		(fp_line
			(start -0.67945 0.3048)
			(end -0.67945 -0.305054)
			(stroke
				(width 0.1)
				(type default)
			)
			(layer "F.Fab")
		)
		(pad "1" smd circle
			(at -0.40005 0 90)
			(size 0 0)
			(layers "F.Cu" "F.Mask" "F.Paste")
			(net "GPU_PRSNT")
		)
		(pad "2" smd circle
			(at 0.40005 0 90)
			(size 0 0)
			(layers "F.Cu" "F.Mask" "F.Paste")
			(net "GPU_PRSNT_R")
		)
	)
	(footprint ""
		(layer "F.Cu")
		(at 80.550512 -339.644736 -90)
		(property "Reference" "PC386"
			(at 0 0 270)
			(layer "F.SilkS")
			(hide yes)
			(effects
				(font
					(size 1.27 1.27)
				)
			)
		)
		(property "Value" ""
			(at 0 0 270)
			(layer "F.Fab")
			(effects
				(font
					(size 1.27 1.27)
				)
			)
		)
		(duplicate_pad_numbers_are_jumpers no)
		(fp_line
			(start -0.7874 0.4064)
			(end -0.7874 -0.4064)
			(stroke
				(width 0.1524)
				(type default)
			)
			(layer "F.SilkS")
		)
		(fp_line
			(start 0.7874 0.4064)
			(end -0.7874 0.4064)
			(stroke
				(width 0.1524)
				(type default)
			)
			(layer "F.SilkS")
		)
		(fp_line
			(start -0.7874 -0.4064)
			(end 0.7874 -0.4064)
			(stroke
				(width 0.1524)
				(type default)
			)
			(layer "F.SilkS")
		)
		(fp_line
			(start 0.7874 -0.4064)
			(end 0.7874 0.4064)
			(stroke
				(width 0.1524)
				(type default)
			)
			(layer "F.SilkS")
		)
		(fp_line
			(start -0.67945 0.3048)
			(end -0.67945 -0.305054)
			(stroke
				(width 0.1)
				(type default)
			)
			(layer "F.Fab")
		)
		(fp_line
			(start -0.12065 0.3048)
			(end -0.67945 0.3048)
			(stroke
				(width 0.1)
				(type default)
			)
			(layer "F.Fab")
		)
		(fp_line
			(start 0.120396 0.3048)
			(end 0.120396 0.2794)
			(stroke
				(width 0.1)
				(type default)
			)
			(layer "F.Fab")
		)
		(fp_line
			(start 0.67945 0.3048)
			(end 0.120396 0.3048)
			(stroke
				(width 0.1)
				(type default)
			)
			(layer "F.Fab")
		)
		(fp_line
			(start -0.12065 0.2794)
			(end -0.12065 0.3048)
			(stroke
				(width 0.1)
				(type default)
			)
			(layer "F.Fab")
		)
		(fp_line
			(start 0.120396 0.2794)
			(end -0.12065 0.2794)
			(stroke
				(width 0.1)
				(type default)
			)
			(layer "F.Fab")
		)
		(fp_line
			(start -0.12065 -0.2794)
			(end 0.12065 -0.2794)
			(stroke
				(width 0.1)
				(type default)
			)
			(layer "F.Fab")
		)
		(fp_line
			(start 0.12065 -0.2794)
			(end 0.12065 -0.3048)
			(stroke
				(width 0.1)
				(type default)
			)
			(layer "F.Fab")
		)
		(fp_line
			(start 0.12065 -0.3048)
			(end 0.67945 -0.3048)
			(stroke
				(width 0.1)
				(type default)
			)
			(layer "F.Fab")
		)
		(fp_line
			(start 0.67945 -0.3048)
			(end 0.67945 0.3048)
			(stroke
				(width 0.1)
				(type default)
			)
			(layer "F.Fab")
		)
		(fp_line
			(start -0.67945 -0.305054)
			(end -0.12065 -0.305054)
			(stroke
				(width 0.1)
				(type default)
			)
			(layer "F.Fab")
		)
		(fp_line
			(start -0.12065 -0.305054)
			(end -0.12065 -0.2794)
			(stroke
				(width 0.1)
				(type default)
			)
			(layer "F.Fab")
		)
		(pad "1" smd circle
			(at -0.40005 0 270)
			(size 0 0)
			(layers "F.Cu" "F.Mask" "F.Paste")
			(net "SW_PVDDCR_CPU1_P1_BOOT2_R")
		)
		(pad "2" smd circle
			(at 0.40005 0 270)
			(size 0 0)
			(layers "F.Cu" "F.Mask" "F.Paste")
			(net "SW_PVDDCR_CPU1_P1_BOOTR2")
		)
	)
)
